(kicad_pcb
	(version 20241229)
	(generator "pcbnew")
	(generator_version "9.0")
	(general
		(thickness 1.6296)
		(legacy_teardrops no)
	)
	(paper "A3")
	(title_block
		(title "Thunderbolt to 10GbE adapter")
		(date "2026-04-21")
		(rev "1.1.0")
		(company "Antmicro Ltd")
		(comment 1 "www.antmicro.com")
		(comment 9 "footprints 64-67 of 703")
	)
	(layers
		(0 "F.Cu" signal)
		(4 "In1.Cu" signal)
		(6 "In2.Cu" signal)
		(8 "In3.Cu" signal)
		(10 "In4.Cu" signal)
		(12 "In5.Cu" signal)
		(14 "In6.Cu" signal)
		(2 "B.Cu" signal)
		(9 "F.Adhes" user "F.Adhesive")
		(11 "B.Adhes" user "B.Adhesive")
		(13 "F.Paste" user)
		(15 "B.Paste" user)
		(5 "F.SilkS" user "F.Silkscreen")
		(7 "B.SilkS" user "B.Silkscreen")
		(1 "F.Mask" user)
		(3 "B.Mask" user)
		(17 "Dwgs.User" user "User.Drawings")
		(19 "Cmts.User" user "User.Comments")
		(21 "Eco1.User" user "User.Eco1")
		(23 "Eco2.User" user "User.Eco2")
		(25 "Edge.Cuts" user)
		(27 "Margin" user)
		(31 "F.CrtYd" user "F.Courtyard")
		(29 "B.CrtYd" user "B.Courtyard")
		(35 "F.Fab" user)
		(33 "B.Fab" user)
	)
	(footprint "antmicro-footprints:C_0402_1005Metric"
		(layer "F.Cu")
		(at 138 77.75)
		(descr "Capacitor SMD 0402")
		(tags "capacitor SMD 0402")
		(property "Reference" "C272"
			(at -3.8 0.45 0)
			(layer "F.SilkS")
			(effects
				(font
					(size 0.7 0.7)
					(thickness 0.15)
				)
				(justify left bottom)
			)
		)
		(property "Value" "C_220n_16V_0402"
			(at -1.022927 2.155213 0)
			(layer "F.Fab")
			(effects
				(font
					(size 0.7 0.7)
					(thickness 0.15)
				)
				(justify left bottom)
			)
		)
		(property "Datasheet" "https://www.murata.com/products/productdetail?partno=GRM155R71C224KA12%23"
			(at 0 0 0)
			(layer "F.Fab")
			(hide yes)
			(effects
				(font
					(size 1.27 1.27)
					(thickness 0.15)
				)
			)
		)
		(property "Description" "SMD Multilayer Ceramic Capacitor, 0.22 µF, 16 V, 0402 [1005 Metric], ± 10%, X7R, GRM Series"
			(at 0 0 0)
			(layer "F.Fab")
			(hide yes)
			(effects
				(font
					(size 1.27 1.27)
					(thickness 0.15)
				)
			)
		)
		(property "MPN" "GRM155R71C224KA12D"
			(at 0 0 0)
			(unlocked yes)
			(layer "F.Fab")
			(hide yes)
			(effects
				(font
					(size 1 1)
					(thickness 0.15)
				)
			)
		)
		(property "Manufacturer" "Murata"
			(at 0 0 0)
			(unlocked yes)
			(layer "F.Fab")
			(hide yes)
			(effects
				(font
					(size 1 1)
					(thickness 0.15)
				)
			)
		)
		(property "License" "Apache-2.0"
			(at 0 0 0)
			(unlocked yes)
			(layer "F.Fab")
			(hide yes)
			(effects
				(font
					(size 1 1)
					(thickness 0.15)
				)
			)
		)
		(property "Author" "Antmicro"
			(at 0 0 0)
			(unlocked yes)
			(layer "F.Fab")
			(hide yes)
			(effects
				(font
					(size 1 1)
					(thickness 0.15)
				)
			)
		)
		(property "Val" "220n"
			(at 0 0 0)
			(unlocked yes)
			(layer "F.Fab")
			(hide yes)
			(effects
				(font
					(size 1 1)
					(thickness 0.15)
				)
			)
		)
		(property "Voltage" "16V"
			(at 0 0 0)
			(unlocked yes)
			(layer "F.Fab")
			(hide yes)
			(effects
				(font
					(size 1 1)
					(thickness 0.15)
				)
			)
		)
		(property "Dielectric" "X7R"
			(at 0 0 0)
			(unlocked yes)
			(layer "F.Fab")
			(hide yes)
			(effects
				(font
					(size 1 1)
					(thickness 0.15)
				)
			)
		)
		(sheetname "/X710-AT2 PCIe/")
		(sheetfile "x710-at2-pcie.kicad_sch")
		(attr smd)
		(fp_rect
			(start -0.925 -0.47)
			(end 0.925 0.47)
			(stroke
				(width 0.05)
				(type default)
			)
			(fill no)
			(layer "F.CrtYd")
		)
		(fp_line
			(start -0.494 -0.25)
			(end 0.504 -0.25)
			(stroke
				(width 0.15)
				(type solid)
			)
			(layer "F.Fab")
		)
		(fp_line
			(start -0.494 0.248)
			(end -0.494 -0.25)
			(stroke
				(width 0.15)
				(type solid)
			)
			(layer "F.Fab")
		)
		(fp_line
			(start 0.504 -0.25)
			(end 0.504 0.248)
			(stroke
				(width 0.15)
				(type solid)
			)
			(layer "F.Fab")
		)
		(fp_line
			(start 0.504 0.248)
			(end -0.494 0.248)
			(stroke
				(width 0.15)
				(type solid)
			)
			(layer "F.Fab")
		)
		(fp_text user "${REFERENCE}"
			(at -0.939 4.599 0)
			(layer "F.Fab")
			(effects
				(font
					(size 0.7 0.7)
					(thickness 0.15)
				)
				(justify left bottom)
			)
		)
		(fp_text user "Author: Antmicro"
			(at -0.939 3.399 0)
			(layer "F.Fab")
			(effects
				(font
					(size 0.7 0.7)
					(thickness 0.15)
				)
				(justify left bottom)
			)
		)
		(fp_text user "License: Apache-2.0"
			(at -0.939 5.799 0)
			(layer "F.Fab")
			(effects
				(font
					(size 0.7 0.7)
					(thickness 0.15)
				)
				(justify left bottom)
			)
		)
		(pad "1" smd roundrect
			(at -0.48 0)
			(size 0.59 0.64)
			(layers "F.Cu" "F.Mask" "F.Paste")
			(roundrect_rratio 0.25)
			(net 602 "/TB Controller/PCIex4.TX2+")
			(pintype "passive")
		)
		(pad "2" smd roundrect
			(at 0.48 0)
			(size 0.59 0.64)
			(layers "F.Cu" "F.Mask" "F.Paste")
			(roundrect_rratio 0.25)
			(net 31 "/X710-AT2 PCIe/PCIe_{x4}_AC.TX2+")
			(pintype "passive")
		)
	)
	(footprint "antmicro-footprints:C_0402_1005Metric"
		(layer "F.Cu")
		(at 117.8 124 180)
		(descr "Capacitor SMD 0402")
		(tags "capacitor SMD 0402")
		(property "Reference" "C46"
			(at -0.8 -0.2 180)
			(layer "F.SilkS")
			(effects
				(font
					(size 0.7 0.7)
					(thickness 0.15)
				)
				(justify left bottom)
			)
		)
		(property "Value" "C_220n_0402"
			(at -1.022927 2.155213 180)
			(layer "F.Fab")
			(effects
				(font
					(size 0.7 0.7)
					(thickness 0.15)
				)
				(justify left bottom)
			)
		)
		(property "Datasheet" "https://www.yageo.com/en/Chart/Download/pdf/CC0402KRX5R6BB224"
			(at 0 0 180)
			(layer "F.Fab")
			(hide yes)
			(effects
				(font
					(size 1.27 1.27)
					(thickness 0.15)
				)
			)
		)
		(property "Description" "SMD Multilayer Ceramic Capacitor, 0.22 µF, 10 V, 0402 [1005 Metric], ± 10%, X5R, CC Series"
			(at 0 0 180)
			(layer "F.Fab")
			(hide yes)
			(effects
				(font
					(size 1.27 1.27)
					(thickness 0.15)
				)
			)
		)
		(property "MPN" "CC0402KRX5R6BB224"
			(at 0 0 180)
			(unlocked yes)
			(layer "F.Fab")
			(hide yes)
			(effects
				(font
					(size 1 1)
					(thickness 0.15)
				)
			)
		)
		(property "Manufacturer" "YAGEO"
			(at 0 0 180)
			(unlocked yes)
			(layer "F.Fab")
			(hide yes)
			(effects
				(font
					(size 1 1)
					(thickness 0.15)
				)
			)
		)
		(property "License" "Apache-2.0"
			(at 0 0 180)
			(unlocked yes)
			(layer "F.Fab")
			(hide yes)
			(effects
				(font
					(size 1 1)
					(thickness 0.15)
				)
			)
		)
		(property "Val" "220n"
			(at 0 0 180)
			(unlocked yes)
			(layer "F.Fab")
			(hide yes)
			(effects
				(font
					(size 1 1)
					(thickness 0.15)
				)
			)
		)
		(property "Voltage" ""
			(at 0 0 180)
			(unlocked yes)
			(layer "F.Fab")
			(hide yes)
			(effects
				(font
					(size 1 1)
					(thickness 0.15)
				)
			)
		)
		(property "Dielectric" ""
			(at 0 0 180)
			(unlocked yes)
			(layer "F.Fab")
			(hide yes)
			(effects
				(font
					(size 1 1)
					(thickness 0.15)
				)
			)
		)
		(property "Author" "Antmicro"
			(at 0 0 180)
			(unlocked yes)
			(layer "F.Fab")
			(hide yes)
			(effects
				(font
					(size 1 1)
					(thickness 0.15)
				)
			)
		)
		(sheetname "/TB Controller/")
		(sheetfile "tb.kicad_sch")
		(attr smd)
		(fp_rect
			(start -0.925 -0.47)
			(end 0.925 0.47)
			(stroke
				(width 0.05)
				(type default)
			)
			(fill no)
			(layer "F.CrtYd")
		)
		(fp_line
			(start 0.504 0.248)
			(end -0.494 0.248)
			(stroke
				(width 0.15)
				(type solid)
			)
			(layer "F.Fab")
		)
		(fp_line
			(start 0.504 -0.25)
			(end 0.504 0.248)
			(stroke
				(width 0.15)
				(type solid)
			)
			(layer "F.Fab")
		)
		(fp_line
			(start -0.494 0.248)
			(end -0.494 -0.25)
			(stroke
				(width 0.15)
				(type solid)
			)
			(layer "F.Fab")
		)
		(fp_line
			(start -0.494 -0.25)
			(end 0.504 -0.25)
			(stroke
				(width 0.15)
				(type solid)
			)
			(layer "F.Fab")
		)
		(fp_text user "License: Apache-2.0"
			(at -0.939 5.799 180)
			(layer "F.Fab")
			(effects
				(font
					(size 0.7 0.7)
					(thickness 0.15)
				)
				(justify left bottom)
			)
		)
		(fp_text user "Author: Antmicro"
			(at -0.939 3.399 180)
			(layer "F.Fab")
			(effects
				(font
					(size 0.7 0.7)
					(thickness 0.15)
				)
				(justify left bottom)
			)
		)
		(fp_text user "${REFERENCE}"
			(at -0.939 4.599 180)
			(layer "F.Fab")
			(effects
				(font
					(size 0.7 0.7)
					(thickness 0.15)
				)
				(justify left bottom)
			)
		)
		(pad "1" smd roundrect
			(at -0.48 0 180)
			(size 0.59 0.64)
			(layers "F.Cu" "F.Mask" "F.Paste")
			(roundrect_rratio 0.25)
			(net 327 "/TB Controller/TB_PCIE_TX2_P")
			(pintype "passive")
		)
		(pad "2" smd roundrect
			(at 0.48 0 180)
			(size 0.59 0.64)
			(layers "F.Cu" "F.Mask" "F.Paste")
			(roundrect_rratio 0.25)
			(net 319 "/TB Controller/PCIex4.RX2+")
			(pintype "passive")
		)
	)
	(footprint "antmicro-footprints:R_0402_1005Metric"
		(layer "F.Cu")
		(at 140.4 138.55)
		(descr "Resistor SMD 0402")
		(tags "resistor SMD 0402")
		(property "Reference" "R11"
			(at -1.2 -1.75 0)
			(layer "F.SilkS")
			(effects
				(font
					(size 0.7 0.7)
					(thickness 0.15)
				)
				(justify left bottom)
			)
		)
		(property "Value" "R_100k_0402"
			(at -1.011843 1.772047 0)
			(layer "F.Fab")
			(effects
				(font
					(size 0.7 0.7)
					(thickness 0.15)
				)
				(justify left bottom)
			)
		)
		(property "Datasheet" "https://www.bourns.com/docs/product-datasheets/cr.pdf"
			(at 0 0 0)
			(layer "F.Fab")
			(hide yes)
			(effects
				(font
					(size 1.27 1.27)
					(thickness 0.15)
				)
			)
		)
		(property "Description" "SMD Chip Resistor, 100 kohm, ± 1%, 62.5 mW, 0402 [1005 Metric], Thick Film, General Purpose"
			(at 0 0 0)
			(layer "F.Fab")
			(hide yes)
			(effects
				(font
					(size 1.27 1.27)
					(thickness 0.15)
				)
			)
		)
		(property "MPN" "CR0402-FX-1003GLF"
			(at 0 0 0)
			(unlocked yes)
			(layer "F.Fab")
			(hide yes)
			(effects
				(font
					(size 1 1)
					(thickness 0.15)
				)
			)
		)
		(property "Manufacturer" "Bourns"
			(at 0 0 0)
			(unlocked yes)
			(layer "F.Fab")
			(hide yes)
			(effects
				(font
					(size 1 1)
					(thickness 0.15)
				)
			)
		)
		(property "License" "Apache-2.0"
			(at 0 0 0)
			(unlocked yes)
			(layer "F.Fab")
			(hide yes)
			(effects
				(font
					(size 1 1)
					(thickness 0.15)
				)
			)
		)
		(property "Val" "100k"
			(at 0 0 0)
			(unlocked yes)
			(layer "F.Fab")
			(hide yes)
			(effects
				(font
					(size 1 1)
					(thickness 0.15)
				)
			)
		)
		(property "Tolerance" "1%"
			(at 0 0 0)
			(unlocked yes)
			(layer "F.Fab")
			(hide yes)
			(effects
				(font
					(size 1 1)
					(thickness 0.15)
				)
			)
		)
		(property "Author" "Antmicro"
			(at 0 0 0)
			(unlocked yes)
			(layer "F.Fab")
			(hide yes)
			(effects
				(font
					(size 1 1)
					(thickness 0.15)
				)
			)
		)
		(sheetname "/PD and TB DC-DC/")
		(sheetfile "PD_and_TB_DC_DC.kicad_sch")
		(attr smd)
		(fp_rect
			(start -0.925 -0.47)
			(end 0.925 0.47)
			(stroke
				(width 0.05)
				(type default)
			)
			(fill no)
			(layer "F.CrtYd")
		)
		(fp_rect
			(start -0.5 -0.25)
			(end 0.5 0.25)
			(stroke
				(width 0.15)
				(type solid)
			)
			(fill no)
			(layer "F.Fab")
		)
		(fp_text user "${REFERENCE}"
			(at -0.95 3.168 0)
			(layer "F.Fab")
			(effects
				(font
					(size 0.7 0.7)
					(thickness 0.15)
				)
				(justify left bottom)
			)
		)
		(fp_text user "Author: Antmicro"
			(at -0.95 4.169 0)
			(layer "F.Fab")
			(effects
				(font
					(size 0.7 0.7)
					(thickness 0.15)
				)
				(justify left bottom)
			)
		)
		(fp_text user "License: Apache-2.0"
			(at -0.95 5.169 0)
			(layer "F.Fab")
			(effects
				(font
					(size 0.7 0.7)
					(thickness 0.15)
				)
				(justify left bottom)
			)
		)
		(pad "1" smd roundrect
			(at -0.48 0)
			(size 0.59 0.64)
			(layers "F.Cu" "F.Mask" "F.Paste")
			(roundrect_rratio 0.25)
			(net 23 "GND")
			(pintype "passive")
		)
		(pad "2" smd roundrect
			(at 0.48 0)
			(size 0.59 0.64)
			(layers "F.Cu" "F.Mask" "F.Paste")
			(roundrect_rratio 0.25)
			(net 374 "/PD and TB DC-DC/HPD")
			(pintype "passive")
		)
	)
	(footprint "antmicro-footprints:C_0402_1005Metric"
		(layer "F.Cu")
		(at 116.4 102.1 180)
		(descr "Capacitor SMD 0402")
		(tags "capacitor SMD 0402")
		(property "Reference" "C16"
			(at 0 8.1 180)
			(layer "F.SilkS")
			(effects
				(font
					(size 0.7 0.7)
					(thickness 0.15)
				)
			)
		)
		(property "Value" "C_220n_0402"
			(at -1.022927 2.155213 180)
			(layer "F.Fab")
			(effects
				(font
					(size 0.7 0.7)
					(thickness 0.15)
				)
				(justify left bottom)
			)
		)
		(property "Datasheet" "https://www.yageo.com/en/Chart/Download/pdf/CC0402KRX5R6BB224"
			(at 0 0 180)
			(layer "F.Fab")
			(hide yes)
			(effects
				(font
					(size 1.27 1.27)
					(thickness 0.15)
				)
			)
		)
		(property "Description" "SMD Multilayer Ceramic Capacitor, 0.22 µF, 10 V, 0402 [1005 Metric], ± 10%, X5R, CC Series"
			(at 0 0 180)
			(layer "F.Fab")
			(hide yes)
			(effects
				(font
					(size 1.27 1.27)
					(thickness 0.15)
				)
			)
		)
		(property "MPN" "CC0402KRX5R6BB224"
			(at 0 0 180)
			(unlocked yes)
			(layer "F.Fab")
			(hide yes)
			(effects
				(font
					(size 1 1)
					(thickness 0.15)
				)
			)
		)
		(property "Manufacturer" "YAGEO"
			(at 0 0 180)
			(unlocked yes)
			(layer "F.Fab")
			(hide yes)
			(effects
				(font
					(size 1 1)
					(thickness 0.15)
				)
			)
		)
		(property "License" "Apache-2.0"
			(at 0 0 180)
			(unlocked yes)
			(layer "F.Fab")
			(hide yes)
			(effects
				(font
					(size 1 1)
					(thickness 0.15)
				)
			)
		)
		(property "Val" "220n"
			(at 0 0 180)
			(unlocked yes)
			(layer "F.Fab")
			(hide yes)
			(effects
				(font
					(size 1 1)
					(thickness 0.15)
				)
			)
		)
		(property "Voltage" ""
			(at 0 0 180)
			(unlocked yes)
			(layer "F.Fab")
			(hide yes)
			(effects
				(font
					(size 1 1)
					(thickness 0.15)
				)
			)
		)
		(property "Dielectric" ""
			(at 0 0 180)
			(unlocked yes)
			(layer "F.Fab")
			(hide yes)
			(effects
				(font
					(size 1 1)
					(thickness 0.15)
				)
			)
		)
		(property "Author" "Antmicro"
			(at 0 0 180)
			(unlocked yes)
			(layer "F.Fab")
			(hide yes)
			(effects
				(font
					(size 1 1)
					(thickness 0.15)
				)
			)
		)
		(sheetname "/PD and TB DC-DC/")
		(sheetfile "PD_and_TB_DC_DC.kicad_sch")
		(attr smd)
		(fp_rect
			(start -0.925 -0.47)
			(end 0.925 0.47)
			(stroke
				(width 0.05)
				(type default)
			)
			(fill no)
			(layer "F.CrtYd")
		)
		(fp_line
			(start 0.504 0.248)
			(end -0.494 0.248)
			(stroke
				(width 0.15)
				(type solid)
			)
			(layer "F.Fab")
		)
		(fp_line
			(start 0.504 -0.25)
			(end 0.504 0.248)
			(stroke
				(width 0.15)
				(type solid)
			)
			(layer "F.Fab")
		)
		(fp_line
			(start -0.494 0.248)
			(end -0.494 -0.25)
			(stroke
				(width 0.15)
				(type solid)
			)
			(layer "F.Fab")
		)
		(fp_line
			(start -0.494 -0.25)
			(end 0.504 -0.25)
			(stroke
				(width 0.15)
				(type solid)
			)
			(layer "F.Fab")
		)
		(fp_text user "License: Apache-2.0"
			(at -0.939 5.799 180)
			(layer "F.Fab")
			(effects
				(font
					(size 0.7 0.7)
					(thickness 0.15)
				)
				(justify left bottom)
			)
		)
		(fp_text user "Author: Antmicro"
			(at -0.939 3.399 180)
			(layer "F.Fab")
			(effects
				(font
					(size 0.7 0.7)
					(thickness 0.15)
				)
				(justify left bottom)
			)
		)
		(fp_text user "${REFERENCE}"
			(at -0.939 4.599 180)
			(layer "F.Fab")
			(effects
				(font
					(size 0.7 0.7)
					(thickness 0.15)
				)
				(justify left bottom)
			)
		)
		(pad "1" smd roundrect
			(at -0.48 0 180)
			(size 0.59 0.64)
			(layers "F.Cu" "F.Mask" "F.Paste")
			(roundrect_rratio 0.25)
			(net 162 "Net-(U2-BST)")
			(pintype "passive")
		)
		(pad "2" smd roundrect
			(at 0.48 0 180)
			(size 0.59 0.64)
			(layers "F.Cu" "F.Mask" "F.Paste")
			(roundrect_rratio 0.25)
			(net 163 "Net-(U2-SW)")
			(pintype "passive")
		)
	)
)
